# BASEBOARD_FAB2 (Tioga Pass) — schematic netlist excerpt (pin names and nets, part order shuffled) for the footprints in the layout excerpt that follows; sources: Cadence DE-HDL packaged netlist, KiCad conversion of Wiwynn_Tioga_Pass_MB.brd

R9G11  RES  0.0 5% CHIP  pkg 0402  page 141 : A = NIC_SER_N_MDI_3_DN ; B = NIC_MDI_SPRV_RJ45_3_R_DN
R2L26  RES  100.0K 1% CHIP  pkg 0402  page 235 : A = P3V3_STBY ; B = VID_PCH_CORE_PVNN_AUX_VID_0
CT15  CAP  1000PF 50V 10% X7R  pkg 0402LF  page 209 : A = A_TSENSE_PVCCIN_CPU1 ; B = GND

(kicad_pcb
	(version 20260206)
	(generator "pcbnew")
	(generator_version "10.0")
	(general
		(thickness 1.6)
		(legacy_teardrops no)
	)
	(paper "A4")
	(title_block
		(title "Wiwynn_Tioga_Pass_MB.brd")
		(comment 1 "Tioga Pass / footprints 4142-4144 of 4770")
	)
	(layers
		(0 "F.Cu" signal "TOP")
		(4 "In1.Cu" signal "L2GND")
		(6 "In2.Cu" signal "L3")
		(8 "In3.Cu" signal "L4GND")
		(10 "In4.Cu" signal "L5")
		(12 "In5.Cu" signal "L6GND")
		(14 "In6.Cu" signal "L7VCC")
		(16 "In7.Cu" signal "L8VCC")
		(18 "In8.Cu" signal "L9GND")
		(20 "In9.Cu" signal "L10")
		(22 "In10.Cu" signal "L11GND")
		(24 "In11.Cu" signal "L12")
		(26 "In12.Cu" signal "L13GND")
		(2 "B.Cu" signal "BOTTOM")
		(9 "F.Adhes" user "F.Adhesive")
		(11 "B.Adhes" user "B.Adhesive")
		(13 "F.Paste" user "Package Geometry/Pastemask Top")
		(15 "B.Paste" user "Package Geometry/Pastemask Bottom")
		(5 "F.SilkS" user "Ref Des/Silkscreen Top")
		(7 "B.SilkS" user "Ref Des/Silkscreen Bottom")
		(1 "F.Mask" user "Board Geometry/Soldermask Top")
		(3 "B.Mask" user "Board Geometry/Soldermask Bottom")
		(17 "Dwgs.User" user "User.Drawings")
		(19 "Cmts.User" user "User.Comments")
		(21 "Eco1.User" user "User.Eco1")
		(23 "Eco2.User" user "User.Eco2")
		(25 "Edge.Cuts" user "Board Geometry/Outline")
		(27 "Margin" user)
		(31 "F.CrtYd" user "Package Geometry/Place Bound Top")
		(29 "B.CrtYd" user "Package Geometry/Place Bound Bottom")
		(35 "F.Fab" user "Ref Des/Assembly Top")
		(33 "B.Fab" user "Ref Des/Assembly Bottom")
	)
	(footprint ""
		(layer "B.Cu")
		(at 477.634554 -2.513838 90)
		(property "Reference" "R9G11"
			(at 0 0 90)
			(layer "B.SilkS")
			(hide yes)
			(effects
				(font
					(size 1.27 1.27)
				)
				(justify mirror)
			)
		)
		(property "Value" ""
			(at 0 0 90)
			(layer "B.Fab")
			(effects
				(font
					(size 1.27 1.27)
				)
				(justify mirror)
			)
		)
		(duplicate_pad_numbers_are_jumpers no)
		(fp_poly
			(pts
				(xy 0.2794 -0.1016) (xy -0.2794 -0.1016) (xy -0.2794 0.9906) (xy 0.2794 0.9906)
			)
			(stroke
				(width 0)
				(type default)
			)
			(fill no)
			(layer "B.CrtYd")
		)
		(fp_line
			(start 0.2794 -0.1016)
			(end 0.2794 0.9906)
			(stroke
				(width 0.1)
				(type default)
			)
			(layer "B.Fab")
		)
		(fp_line
			(start -0.2794 -0.1016)
			(end 0.2794 -0.1016)
			(stroke
				(width 0.1)
				(type default)
			)
			(layer "B.Fab")
		)
		(fp_line
			(start 0.2794 0.9906)
			(end -0.2794 0.9906)
			(stroke
				(width 0.1)
				(type default)
			)
			(layer "B.Fab")
		)
		(fp_line
			(start -0.2794 0.9906)
			(end -0.2794 -0.1016)
			(stroke
				(width 0.1)
				(type default)
			)
			(layer "B.Fab")
		)
		(pad "1" smd rect
			(at 0 0 270)
			(size 0.508 0.508)
			(layers "B.Cu" "B.Mask" "B.Paste")
			(net "NIC_SER_N_MDI_3_DN")
		)
		(pad "2" smd rect
			(at 0 0.889 270)
			(size 0.508 0.508)
			(layers "B.Cu" "B.Mask" "B.Paste")
			(net "NIC_MDI_SPRV_RJ45_3_R_DN")
		)
		(zone
			(layer "B.Cu")
			(hatch none 0.5)
			(connect_pads
				(clearance 0)
			)
			(min_thickness 0.25)
			(keepout
				(tracks allowed)
				(vias not_allowed)
				(pads allowed)
				(copperpour not_allowed)
				(footprints allowed)
			)
			(placement
				(enabled no)
				(sheetname "")
			)
			(fill
				(thermal_gap 0.5)
				(thermal_bridge_width 0.5)
				(island_removal_mode 0)
			)
			(polygon
				(pts
					(xy 477.888554 -2.767838) (xy 477.888554 -2.259838) (xy 478.269554 -2.259838) (xy 478.269554 -2.767838)
				)
			)
		)
		(zone
			(layer "B.Cu")
			(hatch none 0.5)
			(connect_pads
				(clearance 0)
			)
			(min_thickness 0.25)
			(keepout
				(tracks not_allowed)
				(vias allowed)
				(pads allowed)
				(copperpour not_allowed)
				(footprints allowed)
			)
			(placement
				(enabled no)
				(sheetname "")
			)
			(fill
				(thermal_gap 0.5)
				(thermal_bridge_width 0.5)
				(island_removal_mode 0)
			)
			(polygon
				(pts
					(xy 478.269554 -2.767838) (xy 478.269554 -2.259838) (xy 477.888554 -2.259838) (xy 477.888554 -2.767838)
				)
			)
		)
	)
	(footprint ""
		(layer "B.Cu")
		(at 402.463 -152.527 -90)
		(property "Reference" "R2L26"
			(at 0 0 90)
			(layer "B.SilkS")
			(hide yes)
			(effects
				(font
					(size 1.27 1.27)
				)
				(justify mirror)
			)
		)
		(property "Value" ""
			(at 0 0 90)
			(layer "B.Fab")
			(effects
				(font
					(size 1.27 1.27)
				)
				(justify mirror)
			)
		)
		(duplicate_pad_numbers_are_jumpers no)
		(fp_poly
			(pts
				(xy 0.2794 -0.1016) (xy -0.2794 -0.1016) (xy -0.2794 0.9906) (xy 0.2794 0.9906)
			)
			(stroke
				(width 0)
				(type default)
			)
			(fill no)
			(layer "B.CrtYd")
		)
		(fp_line
			(start -0.2794 0.9906)
			(end -0.2794 -0.1016)
			(stroke
				(width 0.1)
				(type default)
			)
			(layer "B.Fab")
		)
		(fp_line
			(start 0.2794 0.9906)
			(end -0.2794 0.9906)
			(stroke
				(width 0.1)
				(type default)
			)
			(layer "B.Fab")
		)
		(fp_line
			(start -0.2794 -0.1016)
			(end 0.2794 -0.1016)
			(stroke
				(width 0.1)
				(type default)
			)
			(layer "B.Fab")
		)
		(fp_line
			(start 0.2794 -0.1016)
			(end 0.2794 0.9906)
			(stroke
				(width 0.1)
				(type default)
			)
			(layer "B.Fab")
		)
		(pad "1" smd rect
			(at 0 0 90)
			(size 0.508 0.508)
			(layers "B.Cu" "B.Mask" "B.Paste")
			(net "P3V3_STBY")
		)
		(pad "2" smd rect
			(at 0 0.889 90)
			(size 0.508 0.508)
			(layers "B.Cu" "B.Mask" "B.Paste")
			(net "VID_PCH_CORE_PVNN_AUX_VID_0")
		)
		(zone
			(layer "B.Cu")
			(hatch none 0.5)
			(connect_pads
				(clearance 0)
			)
			(min_thickness 0.25)
			(keepout
				(tracks not_allowed)
				(vias allowed)
				(pads allowed)
				(copperpour not_allowed)
				(footprints allowed)
			)
			(placement
				(enabled no)
				(sheetname "")
			)
			(fill
				(thermal_gap 0.5)
				(thermal_bridge_width 0.5)
				(island_removal_mode 0)
			)
			(polygon
				(pts
					(xy 401.828 -152.273) (xy 401.828 -152.781) (xy 402.209 -152.781) (xy 402.209 -152.273)
				)
			)
		)
		(zone
			(layer "B.Cu")
			(hatch none 0.5)
			(connect_pads
				(clearance 0)
			)
			(min_thickness 0.25)
			(keepout
				(tracks allowed)
				(vias not_allowed)
				(pads allowed)
				(copperpour not_allowed)
				(footprints allowed)
			)
			(placement
				(enabled no)
				(sheetname "")
			)
			(fill
				(thermal_gap 0.5)
				(thermal_bridge_width 0.5)
				(island_removal_mode 0)
			)
			(polygon
				(pts
					(xy 402.209 -152.273) (xy 402.209 -152.781) (xy 401.828 -152.781) (xy 401.828 -152.273)
				)
			)
		)
	)
	(footprint ""
		(layer "B.Cu")
		(at 30.9372 -88.7222)
		(property "Reference" "CT15"
			(at 0.8382 -0.84963 0)
			(unlocked yes)
			(layer "B.SilkS")
			(effects
				(font
					(size 0.7874 0.5842)
					(thickness 0.1524)
				)
				(justify left mirror)
			)
		)
		(property "Value" ""
			(at 0 0 0)
			(layer "B.Fab")
			(effects
				(font
					(size 1.27 1.27)
				)
				(justify mirror)
			)
		)
		(duplicate_pad_numbers_are_jumpers no)
		(fp_poly
			(pts
				(xy -0.3048 -0.1016) (xy -0.3048 0.9906) (xy 0.3048 0.9906) (xy 0.3048 -0.1016)
			)
			(stroke
				(width 0)
				(type default)
			)
			(fill no)
			(layer "B.CrtYd")
		)
		(fp_line
			(start -0.3048 -0.1016)
			(end 0.3048 -0.1016)
			(stroke
				(width 0.1)
				(type default)
			)
			(layer "B.Fab")
		)
		(fp_line
			(start -0.3048 0.9906)
			(end -0.3048 -0.1016)
			(stroke
				(width 0.1)
				(type default)
			)
			(layer "B.Fab")
		)
		(fp_line
			(start 0.3048 -0.1016)
			(end 0.3048 0.9906)
			(stroke
				(width 0.1)
				(type default)
			)
			(layer "B.Fab")
		)
		(fp_line
			(start 0.3048 0.9906)
			(end -0.3048 0.9906)
			(stroke
				(width 0.1)
				(type default)
			)
			(layer "B.Fab")
		)
		(pad "1" smd rect
			(at 0 0 180)
			(size 0.508 0.508)
			(layers "B.Cu" "B.Mask" "B.Paste")
			(net "A_TSENSE_PVCCIN_CPU1")
		)
		(pad "2" smd rect
			(at 0 0.889 180)
			(size 0.508 0.508)
			(layers "B.Cu" "B.Mask" "B.Paste")
			(net "GND")
		)
		(zone
			(layer "B.Cu")
			(hatch none 0.5)
			(connect_pads
				(clearance 0)
			)
			(min_thickness 0.25)
			(keepout
				(tracks allowed)
				(vias not_allowed)
				(pads allowed)
				(copperpour not_allowed)
				(footprints allowed)
			)
			(placement
				(enabled no)
				(sheetname "")
			)
			(fill
				(thermal_gap 0.5)
				(thermal_bridge_width 0.5)
				(island_removal_mode 0)
			)
			(polygon
				(pts
					(xy 31.1912 -88.4682) (xy 30.6832 -88.4682) (xy 30.6832 -88.0872) (xy 31.1912 -88.0872)
				)
			)
		)
		(zone
			(layer "B.Cu")
			(hatch none 0.5)
			(connect_pads
				(clearance 0)
			)
			(min_thickness 0.25)
			(keepout
				(tracks not_allowed)
				(vias allowed)
				(pads allowed)
				(copperpour not_allowed)
				(footprints allowed)
			)
			(placement
				(enabled no)
				(sheetname "")
			)
			(fill
				(thermal_gap 0.5)
				(thermal_bridge_width 0.5)
				(island_removal_mode 0)
			)
			(polygon
				(pts
					(xy 31.1912 -88.0872) (xy 30.6832 -88.0872) (xy 30.6832 -88.4682) (xy 31.1912 -88.4682)
				)
			)
		)
	)
)
